FILE_TYPE = MULTI_PHYS_TABLE;

PART 'MC74VHC1G07DFT2G'

{========================================================================================}
:VALUE              | PART_TYPE | MATERIAL | PART_NUMBER    = STANDARD | LIFECYCLE      | PART_NUMBER   | JEDEC_TYPE | DESCRIPTION                             | MANUFTR | MANUF_PN           | RD_CMPLS_LVL | CMPLS_LVL | FROM_PJ      | CLASS | DIP_SMD | DATA                       | EE_CHECK_LIST | FP_ECN | PSL | CREATOR | STATUS | MSD | ESD_CDM | ESD_HBM | ESD_MM | PIN_LENGTH_SHORT_PIN | PIN_LENGTH_LONG_PIN | CREATEDAY  ;
{========================================================================================}
 'MC74VHC1G07DFT2G' | 'SMLF'    | 'IC'     | 'AL001G07003'(!) = ''       | ''               | 'AL001G07003' |'SC70-5XA'| 'IC OTHER(5P)MC74VHC1G07DFT2G(SOT-353)' | 'ONS'   | 'MC74VHC1G07DFT2G' | 'EP(V1)'     | 'EP(V1)'  | 'F0T-FISHER' | 'IC'  | ''      | 'ONS_MC74VHC1G07DFT2G.pdf' | ''            | ''     | ''  | ''      | ''     | ''  | ''      | ''      | ''     | '0 MILS'             | '0 MILS'            | '20211021'
 'MC74VHC1G07DFT2G' | 'SMLF'    | 'EMPTY'  | 'AL001G07003'(!) = ''       | ''               | 'AL001G07003' |'SC70-5XA'| 'IC OTHER(5P)MC74VHC1G07DFT2G(SOT-353)' | 'ONS'   | 'MC74VHC1G07DFT2G' | 'EP(V1)'     | 'EP(V1)'  | 'F0T-FISHER' | 'IC'  | ''      | 'ONS_MC74VHC1G07DFT2G.pdf' | ''            | ''     | ''  | ''      | ''     | ''  | ''      | ''      | ''     | '0 MILS'             | '0 MILS'            | '20211021'

END_PART

END.

